(kicad_pcb
	(version 20260206)
	(generator "pcbnew")
	(generator_version "10.0")
	(general
		(thickness 1.6)
		(legacy_teardrops no)
	)
	(paper "A4")
	(title_block
		(title "12092022_DA0F0TMDCD0_F0T_Management_Board_D_brd_V3_OCP.brd")
		(comment 1 "Grand Teton / footprints 1184-1189 of 1440")
	)
	(layers
		(0 "F.Cu" signal "TOP")
		(4 "In1.Cu" signal "GND")
		(6 "In2.Cu" signal "IN1")
		(8 "In3.Cu" signal "GND1")
		(10 "In4.Cu" signal "IN2")
		(12 "In5.Cu" signal "VCC")
		(14 "In6.Cu" signal "VCC1")
		(16 "In7.Cu" signal "IN3")
		(18 "In8.Cu" signal "GND2")
		(20 "In9.Cu" signal "IN4")
		(22 "In10.Cu" signal "GND3")
		(2 "B.Cu" signal "BOTTOM")
		(9 "F.Adhes" user "F.Adhesive")
		(11 "B.Adhes" user "B.Adhesive")
		(13 "F.Paste" user "Package Geometry/Pastemask Top")
		(15 "B.Paste" user "Package Geometry/Pastemask Bottom")
		(5 "F.SilkS" user "Ref Des/Silkscreen Top")
		(7 "B.SilkS" user "Ref Des/Silkscreen Bottom")
		(1 "F.Mask" user "Board Geometry/Soldermask Top")
		(3 "B.Mask" user "Board Geometry/Soldermask Bottom")
		(17 "Dwgs.User" user "User.Drawings")
		(19 "Cmts.User" user "User.Comments")
		(21 "Eco1.User" user "User.Eco1")
		(23 "Eco2.User" user "User.Eco2")
		(25 "Edge.Cuts" user "Board Geometry/Outline")
		(27 "Margin" user)
		(31 "F.CrtYd" user "Package Geometry/Place Bound Top")
		(29 "B.CrtYd" user "Package Geometry/Place Bound Bottom")
		(35 "F.Fab" user "Ref Des/Assembly Top")
		(33 "B.Fab" user "Ref Des/Assembly Bottom")
	)
	(footprint ""
		(layer "B.Cu")
		(at 71.034656 -53.215794)
		(property "Reference" "C6"
			(at 0 0 0)
			(layer "B.SilkS")
			(hide yes)
			(effects
				(font
					(size 1.27 1.27)
				)
				(justify mirror)
			)
		)
		(property "Value" ""
			(at 0 0 0)
			(layer "B.Fab")
			(effects
				(font
					(size 1.27 1.27)
				)
				(justify mirror)
			)
		)
		(duplicate_pad_numbers_are_jumpers no)
		(fp_line
			(start -0.7874 -0.4064)
			(end -0.7874 0.4064)
			(stroke
				(width 0.1524)
				(type default)
			)
			(layer "B.SilkS")
		)
		(fp_line
			(start -0.7874 0.4064)
			(end 0.7874 0.4064)
			(stroke
				(width 0.1524)
				(type default)
			)
			(layer "B.SilkS")
		)
		(fp_line
			(start 0.7874 -0.4064)
			(end -0.7874 -0.4064)
			(stroke
				(width 0.1524)
				(type default)
			)
			(layer "B.SilkS")
		)
		(fp_line
			(start 0.7874 0.4064)
			(end 0.7874 -0.4064)
			(stroke
				(width 0.1524)
				(type default)
			)
			(layer "B.SilkS")
		)
		(fp_line
			(start -0.67945 -0.3048)
			(end -0.67945 0.3048)
			(stroke
				(width 0.1)
				(type default)
			)
			(layer "B.Fab")
		)
		(fp_line
			(start -0.67945 0.3048)
			(end -0.120396 0.3048)
			(stroke
				(width 0.1)
				(type default)
			)
			(layer "B.Fab")
		)
		(fp_line
			(start -0.12065 -0.3048)
			(end -0.67945 -0.3048)
			(stroke
				(width 0.1)
				(type default)
			)
			(layer "B.Fab")
		)
		(fp_line
			(start -0.12065 -0.2794)
			(end -0.12065 -0.3048)
			(stroke
				(width 0.1)
				(type default)
			)
			(layer "B.Fab")
		)
		(fp_line
			(start -0.120396 0.2794)
			(end 0.12065 0.2794)
			(stroke
				(width 0.1)
				(type default)
			)
			(layer "B.Fab")
		)
		(fp_line
			(start -0.120396 0.3048)
			(end -0.120396 0.2794)
			(stroke
				(width 0.1)
				(type default)
			)
			(layer "B.Fab")
		)
		(fp_line
			(start 0.12065 -0.305054)
			(end 0.12065 -0.2794)
			(stroke
				(width 0.1)
				(type default)
			)
			(layer "B.Fab")
		)
		(fp_line
			(start 0.12065 -0.2794)
			(end -0.12065 -0.2794)
			(stroke
				(width 0.1)
				(type default)
			)
			(layer "B.Fab")
		)
		(fp_line
			(start 0.12065 0.2794)
			(end 0.12065 0.3048)
			(stroke
				(width 0.1)
				(type default)
			)
			(layer "B.Fab")
		)
		(fp_line
			(start 0.12065 0.3048)
			(end 0.67945 0.3048)
			(stroke
				(width 0.1)
				(type default)
			)
			(layer "B.Fab")
		)
		(fp_line
			(start 0.67945 -0.305054)
			(end 0.12065 -0.305054)
			(stroke
				(width 0.1)
				(type default)
			)
			(layer "B.Fab")
		)
		(fp_line
			(start 0.67945 0.3048)
			(end 0.67945 -0.305054)
			(stroke
				(width 0.1)
				(type default)
			)
			(layer "B.Fab")
		)
		(pad "1" smd circle
			(at 0.40005 0 180)
			(size 0 0)
			(layers "B.Cu" "B.Mask" "B.Paste")
			(net "P2V5_AUX")
		)
		(pad "2" smd circle
			(at -0.40005 0 180)
			(size 0 0)
			(layers "B.Cu" "B.Mask" "B.Paste")
			(net "GND")
		)
	)
	(footprint ""
		(layer "B.Cu")
		(at 83.947 -58.7248 90)
		(property "Reference" "C132"
			(at 0 0 90)
			(layer "B.SilkS")
			(hide yes)
			(effects
				(font
					(size 1.27 1.27)
				)
				(justify mirror)
			)
		)
		(property "Value" ""
			(at 0 0 90)
			(layer "B.Fab")
			(effects
				(font
					(size 1.27 1.27)
				)
				(justify mirror)
			)
		)
		(duplicate_pad_numbers_are_jumpers no)
		(fp_line
			(start 1.2954 -0.5842)
			(end -1.2954 -0.5842)
			(stroke
				(width 0.1524)
				(type default)
			)
			(layer "B.SilkS")
		)
		(fp_line
			(start 0 -0.5842)
			(end 0 0.5842)
			(stroke
				(width 0.1524)
				(type default)
			)
			(layer "B.SilkS")
		)
		(fp_line
			(start -1.2954 -0.5842)
			(end -1.2954 0.5842)
			(stroke
				(width 0.1524)
				(type default)
			)
			(layer "B.SilkS")
		)
		(fp_line
			(start 1.2954 0.5842)
			(end 1.2954 -0.5842)
			(stroke
				(width 0.1524)
				(type default)
			)
			(layer "B.SilkS")
		)
		(fp_line
			(start -1.2954 0.5842)
			(end 1.2954 0.5842)
			(stroke
				(width 0.1524)
				(type default)
			)
			(layer "B.SilkS")
		)
		(fp_line
			(start 0.8636 -0.4572)
			(end -0.8636 -0.4572)
			(stroke
				(width 0.1)
				(type default)
			)
			(layer "B.Fab")
		)
		(fp_line
			(start -0.8636 -0.4572)
			(end -0.8636 -0.4064)
			(stroke
				(width 0.1)
				(type default)
			)
			(layer "B.Fab")
		)
		(fp_line
			(start 1.1938 -0.4064)
			(end 0.8636 -0.4064)
			(stroke
				(width 0.1)
				(type default)
			)
			(layer "B.Fab")
		)
		(fp_line
			(start 0.8636 -0.4064)
			(end 0.8636 -0.4572)
			(stroke
				(width 0.1)
				(type default)
			)
			(layer "B.Fab")
		)
		(fp_line
			(start -0.8636 -0.4064)
			(end -1.1938 -0.4064)
			(stroke
				(width 0.1)
				(type default)
			)
			(layer "B.Fab")
		)
		(fp_line
			(start -1.1938 -0.4064)
			(end -1.1938 0.4064)
			(stroke
				(width 0.1)
				(type default)
			)
			(layer "B.Fab")
		)
		(fp_line
			(start 1.1938 0.4064)
			(end 1.1938 -0.4064)
			(stroke
				(width 0.1)
				(type default)
			)
			(layer "B.Fab")
		)
		(fp_line
			(start 0.8636 0.4064)
			(end 1.1938 0.4064)
			(stroke
				(width 0.1)
				(type default)
			)
			(layer "B.Fab")
		)
		(fp_line
			(start -0.8636 0.4064)
			(end -0.8636 0.4572)
			(stroke
				(width 0.1)
				(type default)
			)
			(layer "B.Fab")
		)
		(fp_line
			(start -1.1938 0.4064)
			(end -0.8636 0.4064)
			(stroke
				(width 0.1)
				(type default)
			)
			(layer "B.Fab")
		)
		(fp_line
			(start 0.8636 0.4572)
			(end 0.8636 0.4064)
			(stroke
				(width 0.1)
				(type default)
			)
			(layer "B.Fab")
		)
		(fp_line
			(start -0.8636 0.4572)
			(end 0.8636 0.4572)
			(stroke
				(width 0.1)
				(type default)
			)
			(layer "B.Fab")
		)
		(pad "1" smd rect
			(at 0.7366 0)
			(size 0.7112 0.8128)
			(layers "B.Cu" "B.Mask" "B.Paste")
			(net "P1V2_AUX")
		)
		(pad "2" smd rect
			(at -0.7366 0)
			(size 0.7112 0.8128)
			(layers "B.Cu" "B.Mask" "B.Paste")
			(net "GND")
		)
	)
	(footprint ""
		(layer "B.Cu")
		(at 16.2814 -83.693 -90)
		(property "Reference" "R163"
			(at 0 0 90)
			(layer "B.SilkS")
			(hide yes)
			(effects
				(font
					(size 1.27 1.27)
				)
				(justify mirror)
			)
		)
		(property "Value" ""
			(at 0 0 90)
			(layer "B.Fab")
			(effects
				(font
					(size 1.27 1.27)
				)
				(justify mirror)
			)
		)
		(duplicate_pad_numbers_are_jumpers no)
		(fp_line
			(start -0.7874 0.4064)
			(end 0.7874 0.4064)
			(stroke
				(width 0.1524)
				(type default)
			)
			(layer "B.SilkS")
		)
		(fp_line
			(start 0.7874 0.4064)
			(end 0.7874 -0.4064)
			(stroke
				(width 0.1524)
				(type default)
			)
			(layer "B.SilkS")
		)
		(fp_line
			(start -0.7874 -0.4064)
			(end -0.7874 0.4064)
			(stroke
				(width 0.1524)
				(type default)
			)
			(layer "B.SilkS")
		)
		(fp_line
			(start 0.7874 -0.4064)
			(end -0.7874 -0.4064)
			(stroke
				(width 0.1524)
				(type default)
			)
			(layer "B.SilkS")
		)
		(fp_line
			(start -0.67945 0.3048)
			(end -0.120396 0.3048)
			(stroke
				(width 0.1)
				(type default)
			)
			(layer "B.Fab")
		)
		(fp_line
			(start -0.120396 0.3048)
			(end -0.120396 0.2794)
			(stroke
				(width 0.1)
				(type default)
			)
			(layer "B.Fab")
		)
		(fp_line
			(start 0.12065 0.3048)
			(end 0.67945 0.3048)
			(stroke
				(width 0.1)
				(type default)
			)
			(layer "B.Fab")
		)
		(fp_line
			(start 0.67945 0.3048)
			(end 0.67945 -0.305054)
			(stroke
				(width 0.1)
				(type default)
			)
			(layer "B.Fab")
		)
		(fp_line
			(start -0.120396 0.2794)
			(end 0.12065 0.2794)
			(stroke
				(width 0.1)
				(type default)
			)
			(layer "B.Fab")
		)
		(fp_line
			(start 0.12065 0.2794)
			(end 0.12065 0.3048)
			(stroke
				(width 0.1)
				(type default)
			)
			(layer "B.Fab")
		)
		(fp_line
			(start -0.12065 -0.2794)
			(end -0.12065 -0.3048)
			(stroke
				(width 0.1)
				(type default)
			)
			(layer "B.Fab")
		)
		(fp_line
			(start 0.12065 -0.2794)
			(end -0.12065 -0.2794)
			(stroke
				(width 0.1)
				(type default)
			)
			(layer "B.Fab")
		)
		(fp_line
			(start -0.67945 -0.3048)
			(end -0.67945 0.3048)
			(stroke
				(width 0.1)
				(type default)
			)
			(layer "B.Fab")
		)
		(fp_line
			(start -0.12065 -0.3048)
			(end -0.67945 -0.3048)
			(stroke
				(width 0.1)
				(type default)
			)
			(layer "B.Fab")
		)
		(fp_line
			(start 0.12065 -0.305054)
			(end 0.12065 -0.2794)
			(stroke
				(width 0.1)
				(type default)
			)
			(layer "B.Fab")
		)
		(fp_line
			(start 0.67945 -0.305054)
			(end 0.12065 -0.305054)
			(stroke
				(width 0.1)
				(type default)
			)
			(layer "B.Fab")
		)
		(pad "1" smd circle
			(at 0.40005 0 90)
			(size 0 0)
			(layers "B.Cu" "B.Mask" "B.Paste")
			(net "P3V3_AUX")
		)
		(pad "2" smd circle
			(at -0.40005 0 90)
			(size 0 0)
			(layers "B.Cu" "B.Mask" "B.Paste")
			(net "FM_CPU_MSMI_CATERR_LVT3_N")
		)
	)
	(footprint ""
		(layer "B.Cu")
		(at 42.926 -19.431 -90)
		(property "Reference" "R205"
			(at 0 0 90)
			(layer "B.SilkS")
			(hide yes)
			(effects
				(font
					(size 1.27 1.27)
				)
				(justify mirror)
			)
		)
		(property "Value" ""
			(at 0 0 90)
			(layer "B.Fab")
			(effects
				(font
					(size 1.27 1.27)
				)
				(justify mirror)
			)
		)
		(duplicate_pad_numbers_are_jumpers no)
		(fp_line
			(start -0.7874 0.4064)
			(end 0.7874 0.4064)
			(stroke
				(width 0.1524)
				(type default)
			)
			(layer "B.SilkS")
		)
		(fp_line
			(start 0.7874 0.4064)
			(end 0.7874 -0.4064)
			(stroke
				(width 0.1524)
				(type default)
			)
			(layer "B.SilkS")
		)
		(fp_line
			(start -0.7874 -0.4064)
			(end -0.7874 0.4064)
			(stroke
				(width 0.1524)
				(type default)
			)
			(layer "B.SilkS")
		)
		(fp_line
			(start 0.7874 -0.4064)
			(end -0.7874 -0.4064)
			(stroke
				(width 0.1524)
				(type default)
			)
			(layer "B.SilkS")
		)
		(fp_line
			(start -0.67945 0.3048)
			(end -0.120396 0.3048)
			(stroke
				(width 0.1)
				(type default)
			)
			(layer "B.Fab")
		)
		(fp_line
			(start -0.120396 0.3048)
			(end -0.120396 0.2794)
			(stroke
				(width 0.1)
				(type default)
			)
			(layer "B.Fab")
		)
		(fp_line
			(start 0.12065 0.3048)
			(end 0.67945 0.3048)
			(stroke
				(width 0.1)
				(type default)
			)
			(layer "B.Fab")
		)
		(fp_line
			(start 0.67945 0.3048)
			(end 0.67945 -0.305054)
			(stroke
				(width 0.1)
				(type default)
			)
			(layer "B.Fab")
		)
		(fp_line
			(start -0.120396 0.2794)
			(end 0.12065 0.2794)
			(stroke
				(width 0.1)
				(type default)
			)
			(layer "B.Fab")
		)
		(fp_line
			(start 0.12065 0.2794)
			(end 0.12065 0.3048)
			(stroke
				(width 0.1)
				(type default)
			)
			(layer "B.Fab")
		)
		(fp_line
			(start -0.12065 -0.2794)
			(end -0.12065 -0.3048)
			(stroke
				(width 0.1)
				(type default)
			)
			(layer "B.Fab")
		)
		(fp_line
			(start 0.12065 -0.2794)
			(end -0.12065 -0.2794)
			(stroke
				(width 0.1)
				(type default)
			)
			(layer "B.Fab")
		)
		(fp_line
			(start -0.67945 -0.3048)
			(end -0.67945 0.3048)
			(stroke
				(width 0.1)
				(type default)
			)
			(layer "B.Fab")
		)
		(fp_line
			(start -0.12065 -0.3048)
			(end -0.67945 -0.3048)
			(stroke
				(width 0.1)
				(type default)
			)
			(layer "B.Fab")
		)
		(fp_line
			(start 0.12065 -0.305054)
			(end 0.12065 -0.2794)
			(stroke
				(width 0.1)
				(type default)
			)
			(layer "B.Fab")
		)
		(fp_line
			(start 0.67945 -0.305054)
			(end 0.12065 -0.305054)
			(stroke
				(width 0.1)
				(type default)
			)
			(layer "B.Fab")
		)
		(pad "1" smd circle
			(at 0.40005 0 90)
			(size 0 0)
			(layers "B.Cu" "B.Mask" "B.Paste")
			(net "DEBUG_PORT_PRSNT_R")
		)
		(pad "2" smd circle
			(at -0.40005 0 90)
			(size 0 0)
			(layers "B.Cu" "B.Mask" "B.Paste")
			(net "GND")
		)
	)
	(footprint ""
		(layer "B.Cu")
		(at 54.308502 -70.420484 90)
		(property "Reference" "R791"
			(at 0 0 90)
			(layer "B.SilkS")
			(hide yes)
			(effects
				(font
					(size 1.27 1.27)
				)
				(justify mirror)
			)
		)
		(property "Value" ""
			(at 0 0 90)
			(layer "B.Fab")
			(effects
				(font
					(size 1.27 1.27)
				)
				(justify mirror)
			)
		)
		(duplicate_pad_numbers_are_jumpers no)
		(fp_line
			(start 0.7874 -0.4064)
			(end -0.7874 -0.4064)
			(stroke
				(width 0.1524)
				(type default)
			)
			(layer "B.SilkS")
		)
		(fp_line
			(start -0.7874 -0.4064)
			(end -0.7874 0.4064)
			(stroke
				(width 0.1524)
				(type default)
			)
			(layer "B.SilkS")
		)
		(fp_line
			(start 0.7874 0.4064)
			(end 0.7874 -0.4064)
			(stroke
				(width 0.1524)
				(type default)
			)
			(layer "B.SilkS")
		)
		(fp_line
			(start -0.7874 0.4064)
			(end 0.7874 0.4064)
			(stroke
				(width 0.1524)
				(type default)
			)
			(layer "B.SilkS")
		)
		(fp_line
			(start 0.67945 -0.305054)
			(end 0.12065 -0.305054)
			(stroke
				(width 0.1)
				(type default)
			)
			(layer "B.Fab")
		)
		(fp_line
			(start 0.12065 -0.305054)
			(end 0.12065 -0.2794)
			(stroke
				(width 0.1)
				(type default)
			)
			(layer "B.Fab")
		)
		(fp_line
			(start -0.12065 -0.3048)
			(end -0.67945 -0.3048)
			(stroke
				(width 0.1)
				(type default)
			)
			(layer "B.Fab")
		)
		(fp_line
			(start -0.67945 -0.3048)
			(end -0.67945 0.3048)
			(stroke
				(width 0.1)
				(type default)
			)
			(layer "B.Fab")
		)
		(fp_line
			(start 0.12065 -0.2794)
			(end -0.12065 -0.2794)
			(stroke
				(width 0.1)
				(type default)
			)
			(layer "B.Fab")
		)
		(fp_line
			(start -0.12065 -0.2794)
			(end -0.12065 -0.3048)
			(stroke
				(width 0.1)
				(type default)
			)
			(layer "B.Fab")
		)
		(fp_line
			(start 0.12065 0.2794)
			(end 0.12065 0.3048)
			(stroke
				(width 0.1)
				(type default)
			)
			(layer "B.Fab")
		)
		(fp_line
			(start -0.120396 0.2794)
			(end 0.12065 0.2794)
			(stroke
				(width 0.1)
				(type default)
			)
			(layer "B.Fab")
		)
		(fp_line
			(start 0.67945 0.3048)
			(end 0.67945 -0.305054)
			(stroke
				(width 0.1)
				(type default)
			)
			(layer "B.Fab")
		)
		(fp_line
			(start 0.12065 0.3048)
			(end 0.67945 0.3048)
			(stroke
				(width 0.1)
				(type default)
			)
			(layer "B.Fab")
		)
		(fp_line
			(start -0.120396 0.3048)
			(end -0.120396 0.2794)
			(stroke
				(width 0.1)
				(type default)
			)
			(layer "B.Fab")
		)
		(fp_line
			(start -0.67945 0.3048)
			(end -0.120396 0.3048)
			(stroke
				(width 0.1)
				(type default)
			)
			(layer "B.Fab")
		)
		(pad "1" smd circle
			(at 0.40005 0 270)
			(size 0 0)
			(layers "B.Cu" "B.Mask" "B.Paste")
			(net "P2V5_AUX")
		)
		(pad "2" smd circle
			(at -0.40005 0 270)
			(size 0 0)
			(layers "B.Cu" "B.Mask" "B.Paste")
			(net "P2V5_SENSOR")
		)
	)
	(footprint ""
		(layer "B.Cu")
		(at 35.052 -106.3625 -90)
		(property "Reference" "R230"
			(at 0 0 90)
			(layer "B.SilkS")
			(hide yes)
			(effects
				(font
					(size 1.27 1.27)
				)
				(justify mirror)
			)
		)
		(property "Value" ""
			(at 0 0 90)
			(layer "B.Fab")
			(effects
				(font
					(size 1.27 1.27)
				)
				(justify mirror)
			)
		)
		(duplicate_pad_numbers_are_jumpers no)
		(fp_line
			(start -0.7874 0.4064)
			(end 0.7874 0.4064)
			(stroke
				(width 0.1524)
				(type default)
			)
			(layer "B.SilkS")
		)
		(fp_line
			(start 0.7874 0.4064)
			(end 0.7874 -0.4064)
			(stroke
				(width 0.1524)
				(type default)
			)
			(layer "B.SilkS")
		)
		(fp_line
			(start -0.7874 -0.4064)
			(end -0.7874 0.4064)
			(stroke
				(width 0.1524)
				(type default)
			)
			(layer "B.SilkS")
		)
		(fp_line
			(start 0.7874 -0.4064)
			(end -0.7874 -0.4064)
			(stroke
				(width 0.1524)
				(type default)
			)
			(layer "B.SilkS")
		)
		(fp_line
			(start -0.67945 0.3048)
			(end -0.120396 0.3048)
			(stroke
				(width 0.1)
				(type default)
			)
			(layer "B.Fab")
		)
		(fp_line
			(start -0.120396 0.3048)
			(end -0.120396 0.2794)
			(stroke
				(width 0.1)
				(type default)
			)
			(layer "B.Fab")
		)
		(fp_line
			(start 0.12065 0.3048)
			(end 0.67945 0.3048)
			(stroke
				(width 0.1)
				(type default)
			)
			(layer "B.Fab")
		)
		(fp_line
			(start 0.67945 0.3048)
			(end 0.67945 -0.305054)
			(stroke
				(width 0.1)
				(type default)
			)
			(layer "B.Fab")
		)
		(fp_line
			(start -0.120396 0.2794)
			(end 0.12065 0.2794)
			(stroke
				(width 0.1)
				(type default)
			)
			(layer "B.Fab")
		)
		(fp_line
			(start 0.12065 0.2794)
			(end 0.12065 0.3048)
			(stroke
				(width 0.1)
				(type default)
			)
			(layer "B.Fab")
		)
		(fp_line
			(start -0.12065 -0.2794)
			(end -0.12065 -0.3048)
			(stroke
				(width 0.1)
				(type default)
			)
			(layer "B.Fab")
		)
		(fp_line
			(start 0.12065 -0.2794)
			(end -0.12065 -0.2794)
			(stroke
				(width 0.1)
				(type default)
			)
			(layer "B.Fab")
		)
		(fp_line
			(start -0.67945 -0.3048)
			(end -0.67945 0.3048)
			(stroke
				(width 0.1)
				(type default)
			)
			(layer "B.Fab")
		)
		(fp_line
			(start -0.12065 -0.3048)
			(end -0.67945 -0.3048)
			(stroke
				(width 0.1)
				(type default)
			)
			(layer "B.Fab")
		)
		(fp_line
			(start 0.12065 -0.305054)
			(end 0.12065 -0.2794)
			(stroke
				(width 0.1)
				(type default)
			)
			(layer "B.Fab")
		)
		(fp_line
			(start 0.67945 -0.305054)
			(end 0.12065 -0.305054)
			(stroke
				(width 0.1)
				(type default)
			)
			(layer "B.Fab")
		)
		(pad "1" smd circle
			(at 0.40005 0 90)
			(size 0 0)
			(layers "B.Cu" "B.Mask" "B.Paste")
			(net "P3V3_AUX")
		)
		(pad "2" smd circle
			(at -0.40005 0 90)
			(size 0 0)
			(layers "B.Cu" "B.Mask" "B.Paste")
			(net "JTAG_MB_TDO")
		)
	)
)
